(kicad_pcb
	(version 20260206)
	(generator "pcbnew")
	(generator_version "10.0")
	(general
		(thickness 1.6)
		(legacy_teardrops no)
	)
	(paper "A4")
	(title_block
		(title "m-2 — Lightning_M.2_BRD.brd")
		(comment 1 "Lightning (Wiwynn / Facebook NVMe JBOF) / footprints 79-81 of 157")
	)
	(layers
		(0 "F.Cu" signal "TOP")
		(4 "In1.Cu" signal "L2GND")
		(6 "In2.Cu" signal "L3")
		(8 "In3.Cu" signal "L4GND")
		(10 "In4.Cu" signal "L5GND")
		(12 "In5.Cu" signal "L6")
		(14 "In6.Cu" signal "L7GND")
		(2 "B.Cu" signal "BOTTOM")
		(9 "F.Adhes" user "F.Adhesive")
		(11 "B.Adhes" user "B.Adhesive")
		(13 "F.Paste" user "Package Geometry/Pastemask Top")
		(15 "B.Paste" user "Package Geometry/Pastemask Bottom")
		(5 "F.SilkS" user "Ref Des/Silkscreen Top")
		(7 "B.SilkS" user "Ref Des/Silkscreen Bottom")
		(1 "F.Mask" user "Board Geometry/Soldermask Top")
		(3 "B.Mask" user "Board Geometry/Soldermask Bottom")
		(17 "Dwgs.User" user "User.Drawings")
		(19 "Cmts.User" user "User.Comments")
		(21 "Eco1.User" user "User.Eco1")
		(23 "Eco2.User" user "User.Eco2")
		(25 "Edge.Cuts" user "Board Geometry/Outline")
		(27 "Margin" user)
		(31 "F.CrtYd" user "Package Geometry/Place Bound Top")
		(29 "B.CrtYd" user "Package Geometry/Place Bound Bottom")
		(35 "F.Fab" user "Ref Des/Assembly Top")
		(33 "B.Fab" user "Ref Des/Assembly Bottom")
	)
	(footprint ""
		(layer "F.Cu")
		(at 55.753 -82.296 90)
		(property "Reference" "PL3"
			(at 0 0 90)
			(layer "F.SilkS")
			(hide yes)
			(effects
				(font
					(size 1.27 1.27)
				)
			)
		)
		(property "Value" "IND-1D5UH-107-GP"
			(at -0.509016 -7.542784 90)
			(unlocked yes)
			(layer "F.Fab")
			(hide yes)
			(effects
				(font
					(size 1.016 1.016)
					(thickness 0.1524)
				)
			)
		)
		(property "Device Type" "L7774-1711H197"
			(at -0.509016 -9.066784 90)
			(unlocked yes)
			(layer "F.Fab")
			(hide yes)
			(effects
				(font
					(size 1.016 1.016)
					(thickness 0.1524)
				)
			)
		)
		(duplicate_pad_numbers_are_jumpers no)
		(fp_line
			(start 3.9497 -4.7371)
			(end 3.9497 4.7371)
			(stroke
				(width 0.1524)
				(type default)
			)
			(layer "F.SilkS")
		)
		(fp_line
			(start -3.9497 -4.7371)
			(end 3.9497 -4.7371)
			(stroke
				(width 0.1524)
				(type default)
			)
			(layer "F.SilkS")
		)
		(fp_line
			(start 3.9497 4.7371)
			(end -3.9497 4.7371)
			(stroke
				(width 0.1524)
				(type default)
			)
			(layer "F.SilkS")
		)
		(fp_line
			(start -3.9497 4.7371)
			(end -3.9497 -4.7371)
			(stroke
				(width 0.1524)
				(type default)
			)
			(layer "F.SilkS")
		)
		(fp_rect
			(start -3.6957 3.8481)
			(end 3.6957 -3.8481)
			(stroke
				(width 0)
				(type default)
			)
			(fill no)
			(layer "F.CrtYd")
		)
		(fp_poly
			(pts
				(xy -4.2037 4.8133) (xy -4.2037 -2.208022) (xy -3.6957 -2.208022) (xy -3.6957 3.8481) (xy 3.6957 3.8481)
				(xy 3.6957 -3.8481) (xy -3.6957 -3.8481) (xy -3.6957 -2.208276) (xy -4.2037 -2.208276) (xy -4.2037 -4.8133)
				(xy 4.2037 -4.8133) (xy 4.2037 4.8133)
			)
			(stroke
				(width 0)
				(type default)
			)
			(fill no)
			(layer "F.CrtYd")
		)
		(fp_rect
			(start -4.2037 4.8133)
			(end 4.2037 -4.8133)
			(stroke
				(width 0)
				(type default)
			)
			(fill no)
			(layer "F.Fab")
		)
		(pad "1" smd rect
			(at 0 -3.189478 90)
			(size 1.3462 2.5908)
			(layers "F.Cu" "F.Mask" "F.Paste")
			(net "P3V3_DEV_LL")
		)
		(pad "2" smd rect
			(at 0 3.189478 90)
			(size 1.3462 2.5908)
			(layers "F.Cu" "F.Mask" "F.Paste")
			(net "P3V3_PWR")
		)
	)
	(footprint ""
		(layer "F.Cu")
		(at 31.369 -78.74)
		(property "Reference" "R41"
			(at 0 0 0)
			(layer "F.SilkS")
			(hide yes)
			(effects
				(font
					(size 1.27 1.27)
				)
			)
		)
		(property "Value" "0R2J-2-GP"
			(at 0.064008 -3.993896 0)
			(unlocked yes)
			(layer "F.Fab")
			(hide yes)
			(effects
				(font
					(size 1.016 1.016)
					(thickness 0.1524)
				)
			)
		)
		(property "Device Type" "R402H16"
			(at 0.064008 -5.517896 0)
			(unlocked yes)
			(layer "F.Fab")
			(hide yes)
			(effects
				(font
					(size 1.016 1.016)
					(thickness 0.1524)
				)
			)
		)
		(duplicate_pad_numbers_are_jumpers no)
		(fp_line
			(start -0.508 -0.9398)
			(end -0.508 0.9398)
			(stroke
				(width 0.1524)
				(type default)
			)
			(layer "F.SilkS")
		)
		(fp_line
			(start 0.508 -0.9398)
			(end -0.508 -0.9398)
			(stroke
				(width 0.1524)
				(type default)
			)
			(layer "F.SilkS")
		)
		(fp_rect
			(start -0.508 0.9398)
			(end 0.508 -0.9398)
			(stroke
				(width 0)
				(type default)
			)
			(fill no)
			(layer "F.CrtYd")
		)
		(fp_rect
			(start -0.508 0.9398)
			(end 0.508 -0.9398)
			(stroke
				(width 0)
				(type default)
			)
			(fill no)
			(layer "F.Fab")
		)
		(pad "1" smd custom
			(at 0 -0.4445)
			(size 0.1397 0.1397)
			(layers "F.Cu" "F.Mask" "F.Paste")
			(net "Z50_SSD_B1_SMB_CLK_R")
			(options
				(clearance outline)
				(anchor circle)
			)
			(primitives
				(gr_poly
					(pts
						(arc
							(start -0.1778 -0.2794)
							(mid -0.249642 -0.249642)
							(end -0.2794 -0.1778)
						)
						(arc
							(start -0.2794 0.1778)
							(mid -0.249642 0.249642)
							(end -0.1778 0.2794)
						)
						(arc
							(start 0.1778 0.2794)
							(mid 0.249642 0.249642)
							(end 0.2794 0.1778)
						)
						(arc
							(start 0.2794 -0.1778)
							(mid 0.249642 -0.249642)
							(end 0.1778 -0.2794)
						)
					)
					(width 0)
					(fill yes)
				)
			)
		)
		(pad "2" smd custom
			(at 0 0.4445)
			(size 0.1397 0.1397)
			(layers "F.Cu" "F.Mask" "F.Paste")
			(net "Z50_SSD_B1_SMB_CLK_LL")
			(options
				(clearance outline)
				(anchor circle)
			)
			(primitives
				(gr_poly
					(pts
						(arc
							(start -0.1778 -0.2794)
							(mid -0.249642 -0.249642)
							(end -0.2794 -0.1778)
						)
						(arc
							(start -0.2794 0.1778)
							(mid -0.249642 0.249642)
							(end -0.1778 0.2794)
						)
						(arc
							(start 0.1778 0.2794)
							(mid 0.249642 0.249642)
							(end 0.2794 0.1778)
						)
						(arc
							(start 0.2794 -0.1778)
							(mid 0.249642 -0.249642)
							(end 0.1778 -0.2794)
						)
					)
					(width 0)
					(fill yes)
				)
			)
		)
	)
	(footprint ""
		(layer "F.Cu")
		(at 74.676 -38.735 180)
		(property "Reference" "R44"
			(at 0 0 180)
			(layer "F.SilkS")
			(hide yes)
			(effects
				(font
					(size 1.27 1.27)
				)
			)
		)
		(property "Value" "47KR2F-GP"
			(at 0.064008 -3.993896 180)
			(unlocked yes)
			(layer "F.Fab")
			(hide yes)
			(effects
				(font
					(size 1.016 1.016)
					(thickness 0.1524)
				)
			)
		)
		(property "Device Type" "R402H16"
			(at 0.064008 -5.517896 180)
			(unlocked yes)
			(layer "F.Fab")
			(hide yes)
			(effects
				(font
					(size 1.016 1.016)
					(thickness 0.1524)
				)
			)
		)
		(duplicate_pad_numbers_are_jumpers no)
		(fp_line
			(start 0.508 -0.9398)
			(end -0.508 -0.9398)
			(stroke
				(width 0.1524)
				(type default)
			)
			(layer "F.SilkS")
		)
		(fp_line
			(start -0.508 -0.9398)
			(end -0.508 0.9398)
			(stroke
				(width 0.1524)
				(type default)
			)
			(layer "F.SilkS")
		)
		(fp_rect
			(start -0.508 0.9398)
			(end 0.508 -0.9398)
			(stroke
				(width 0)
				(type default)
			)
			(fill no)
			(layer "F.CrtYd")
		)
		(fp_rect
			(start -0.508 0.9398)
			(end 0.508 -0.9398)
			(stroke
				(width 0)
				(type default)
			)
			(fill no)
			(layer "F.Fab")
		)
		(pad "1" smd custom
			(at 0 -0.4445 180)
			(size 0.1397 0.1397)
			(layers "F.Cu" "F.Mask" "F.Paste")
			(net "P3V3_DPB")
			(options
				(clearance outline)
				(anchor circle)
			)
			(primitives
				(gr_poly
					(pts
						(arc
							(start -0.1778 -0.2794)
							(mid -0.249642 -0.249642)
							(end -0.2794 -0.1778)
						)
						(arc
							(start -0.2794 0.1778)
							(mid -0.249642 0.249642)
							(end -0.1778 0.2794)
						)
						(arc
							(start 0.1778 0.2794)
							(mid 0.249642 0.249642)
							(end 0.2794 0.1778)
						)
						(arc
							(start 0.2794 -0.1778)
							(mid 0.249642 -0.249642)
							(end 0.1778 -0.2794)
						)
					)
					(width 0)
					(fill yes)
				)
			)
		)
		(pad "2" smd custom
			(at 0 0.4445 180)
			(size 0.1397 0.1397)
			(layers "F.Cu" "F.Mask" "F.Paste")
			(net "Z50_SSD_A_PRSNT#")
			(options
				(clearance outline)
				(anchor circle)
			)
			(primitives
				(gr_poly
					(pts
						(arc
							(start -0.1778 -0.2794)
							(mid -0.249642 -0.249642)
							(end -0.2794 -0.1778)
						)
						(arc
							(start -0.2794 0.1778)
							(mid -0.249642 0.249642)
							(end -0.1778 0.2794)
						)
						(arc
							(start 0.1778 0.2794)
							(mid 0.249642 0.249642)
							(end 0.2794 0.1778)
						)
						(arc
							(start 0.2794 -0.1778)
							(mid 0.249642 -0.249642)
							(end 0.1778 -0.2794)
						)
					)
					(width 0)
					(fill yes)
				)
			)
		)
	)
)
